(kicad_pcb
	(version 20260206)
	(generator "pcbnew")
	(generator_version "10.0")
	(general
		(thickness 1.6)
		(legacy_teardrops no)
	)
	(paper "A4")
	(title_block
		(title "04192023_DAF0TMB3IC0_F0TG_MB_C_brd_V02_OCP.brd")
		(comment 1 "Grand Teton / footprint 3102 of 8354 (U6011), pads 224-336 of 354")
	)
	(layers
		(0 "F.Cu" signal "TOP")
		(4 "In1.Cu" signal "GND")
		(6 "In2.Cu" signal "IN1")
		(8 "In3.Cu" signal "GND1")
		(10 "In4.Cu" signal "IN2")
		(12 "In5.Cu" signal "GND2")
		(14 "In6.Cu" signal "IN3")
		(16 "In7.Cu" signal "GND3")
		(18 "In8.Cu" signal "VCC")
		(20 "In9.Cu" signal "VCC1")
		(22 "In10.Cu" signal "GND4")
		(24 "In11.Cu" signal "IN4")
		(26 "In12.Cu" signal "GND5")
		(28 "In13.Cu" signal "IN5")
		(30 "In14.Cu" signal "GND6")
		(32 "In15.Cu" signal "IN6")
		(34 "In16.Cu" signal "GND7")
		(2 "B.Cu" signal "BOTTOM")
		(9 "F.Adhes" user "F.Adhesive")
		(11 "B.Adhes" user "B.Adhesive")
		(13 "F.Paste" user "Package Geometry/Pastemask Top")
		(15 "B.Paste" user "Package Geometry/Pastemask Bottom")
		(5 "F.SilkS" user "Ref Des/Silkscreen Top")
		(7 "B.SilkS" user "Ref Des/Silkscreen Bottom")
		(1 "F.Mask" user "Board Geometry/Soldermask Top")
		(3 "B.Mask" user "Board Geometry/Soldermask Bottom")
		(17 "Dwgs.User" user "User.Drawings")
		(19 "Cmts.User" user "User.Comments")
		(21 "Eco1.User" user "User.Eco1")
		(23 "Eco2.User" user "User.Eco2")
		(25 "Edge.Cuts" user "Board Geometry/Outline")
		(27 "Margin" user)
		(31 "F.CrtYd" user "Package Geometry/Place Bound Top")
		(29 "B.CrtYd" user "Package Geometry/Place Bound Bottom")
		(35 "F.Fab" user "Ref Des/Assembly Top")
		(33 "B.Fab" user "Ref Des/Assembly Bottom")
	)
	(footprint ""
		(layer "F.Cu")
		(at 344.9955 -395.724634)
		(property "Reference" "U6011"
			(at -8.11784 -7.526528 0)
			(unlocked yes)
			(layer "F.SilkS")
			(effects
				(font
					(size 0.7874 0.5842)
					(thickness 0.1524)
				)
				(justify left)
			)
		)
		(property "Value" ""
			(at 0 0 0)
			(layer "F.Fab")
			(effects
				(font
					(size 1.27 1.27)
				)
			)
		)
		(duplicate_pad_numbers_are_jumpers no)
		(pad "DY32" smd circle
			(at -5.997448 2.724912)
			(size 0.381 0.381)
			(layers "F.Cu" "F.Mask" "F.Paste")
			(net "GND")
		)
		(pad "E8" smd circle
			(at 10.366502 -1.988312)
			(size 0.3048 0.3048)
			(layers "F.Cu" "F.Mask" "F.Paste")
			(net "JTAG_TRST_RT_CPU0_P1_N")
		)
		(pad "E11" smd circle
			(at 10.366502 -1.388364)
			(size 0.3048 0.3048)
			(layers "F.Cu" "F.Mask" "F.Paste")
			(net "RXDET_BYP_RT_CPU0_P1")
		)
		(pad "E14" smd circle
			(at 10.366502 -0.788416)
			(size 0.3048 0.3048)
			(layers "F.Cu" "F.Mask" "F.Paste")
			(net "GND")
		)
		(pad "E18" smd circle
			(at 10.366502 -0.188468)
			(size 0.3048 0.3048)
			(layers "F.Cu" "F.Mask" "F.Paste")
			(net "Net_2206")
		)
		(pad "E27" smd circle
			(at 10.366502 1.61163)
			(size 0.3048 0.3048)
			(layers "F.Cu" "F.Mask" "F.Paste")
			(net "GND")
		)
		(pad "E30" smd circle
			(at 10.366502 2.211578)
			(size 0.3048 0.3048)
			(layers "F.Cu" "F.Mask" "F.Paste")
			(net "GND")
		)
		(pad "E33" smd circle
			(at 10.366502 2.811526)
			(size 0.3048 0.3048)
			(layers "F.Cu" "F.Mask" "F.Paste")
			(net "GND")
		)
		(pad "EA2" smd circle
			(at -6.050026 -3.41884)
			(size 0.3048 0.3048)
			(layers "F.Cu" "F.Mask" "F.Paste")
			(net "GND")
		)
		(pad "EA34" smd circle
			(at -6.050026 3.420364)
			(size 0.3048 0.3048)
			(layers "F.Cu" "F.Mask" "F.Paste")
			(net "GND")
		)
		(pad "EB1" smd oval
			(at -6.35 -3.938524)
			(size 0.254 0.3302)
			(layers "F.Cu" "F.Mask" "F.Paste")
			(net "GND")
		)
		(pad "EB35" smd oval
			(at -6.35 3.940048)
			(size 0.254 0.3302)
			(layers "F.Cu" "F.Mask" "F.Paste")
			(net "GND")
		)
		(pad "EC7" smd circle
			(at -6.397498 -2.12471)
			(size 0.381 0.381)
			(layers "F.Cu" "F.Mask" "F.Paste")
			(net "P5E_CPU0_P1_TX_BUF_DP<2>")
		)
		(pad "EC26" smd circle
			(at -6.397498 1.339342)
			(size 0.381 0.381)
			(layers "F.Cu" "F.Mask" "F.Paste")
			(net "P5E_CPU0_P1_RX_DP<2>")
		)
		(pad "ED2" smd circle
			(at -6.649974 -3.41884)
			(size 0.3048 0.3048)
			(layers "F.Cu" "F.Mask" "F.Paste")
			(net "P5E_CPU0_P1_RX_BUF_DN<2>")
		)
		(pad "ED34" smd circle
			(at -6.649974 3.420364)
			(size 0.3048 0.3048)
			(layers "F.Cu" "F.Mask" "F.Paste")
			(net "P5E_CPU0_P1_TX_C_DN<2>")
		)
		(pad "EE10" smd circle
			(at -6.797294 -1.431798)
			(size 0.381 0.381)
			(layers "F.Cu" "F.Mask" "F.Paste")
			(net "P5E_CPU0_P1_TX_BUF_DN<2>")
		)
		(pad "EE29" smd circle
			(at -6.797294 2.032254)
			(size 0.381 0.381)
			(layers "F.Cu" "F.Mask" "F.Paste")
			(net "P5E_CPU0_P1_RX_DN<2>")
		)
		(pad "EF1" smd oval
			(at -6.949948 -3.938524)
			(size 0.254 0.3302)
			(layers "F.Cu" "F.Mask" "F.Paste")
			(net "P5E_CPU0_P1_RX_BUF_DP<2>")
		)
		(pad "EF35" smd oval
			(at -6.949948 3.940048)
			(size 0.254 0.3302)
			(layers "F.Cu" "F.Mask" "F.Paste")
			(net "P5E_CPU0_P1_TX_C_DP<2>")
		)
		(pad "EG4" smd circle
			(at -7.197344 -2.817368)
			(size 0.381 0.381)
			(layers "F.Cu" "F.Mask" "F.Paste")
			(net "GND")
		)
		(pad "EG13" smd circle
			(at -7.197344 -0.79629)
			(size 0.3048 0.3048)
			(layers "F.Cu" "F.Mask" "F.Paste")
			(net "GND")
		)
		(pad "EG17" smd circle
			(at -7.197344 -0.296164)
			(size 0.3048 0.3048)
			(layers "F.Cu" "F.Mask" "F.Paste")
			(net "P0V9_CPU0_RT1_2A")
		)
		(pad "EG20" smd circle
			(at -7.197344 0.203708)
			(size 0.3048 0.3048)
			(layers "F.Cu" "F.Mask" "F.Paste")
			(net "P0V9_CPU0_RT1_2A")
		)
		(pad "EG22" smd circle
			(at -7.197344 0.703834)
			(size 0.3048 0.3048)
			(layers "F.Cu" "F.Mask" "F.Paste")
			(net "GND")
		)
		(pad "EG32" smd circle
			(at -7.197344 2.724912)
			(size 0.381 0.381)
			(layers "F.Cu" "F.Mask" "F.Paste")
			(net "GND")
		)
		(pad "EH2" smd circle
			(at -7.249922 -3.41884)
			(size 0.3048 0.3048)
			(layers "F.Cu" "F.Mask" "F.Paste")
			(net "GND")
		)
		(pad "EH34" smd circle
			(at -7.249922 3.420364)
			(size 0.3048 0.3048)
			(layers "F.Cu" "F.Mask" "F.Paste")
			(net "GND")
		)
		(pad "EJ1" smd oval
			(at -7.549896 -3.938524)
			(size 0.254 0.3302)
			(layers "F.Cu" "F.Mask" "F.Paste")
			(net "GND")
		)
		(pad "EJ35" smd oval
			(at -7.549896 3.940048)
			(size 0.254 0.3302)
			(layers "F.Cu" "F.Mask" "F.Paste")
			(net "GND")
		)
		(pad "EK7" smd circle
			(at -7.597394 -2.12471)
			(size 0.381 0.381)
			(layers "F.Cu" "F.Mask" "F.Paste")
			(net "P5E_CPU0_P1_TX_BUF_DP<1>")
		)
		(pad "EK26" smd circle
			(at -7.597394 1.339342)
			(size 0.381 0.381)
			(layers "F.Cu" "F.Mask" "F.Paste")
			(net "P5E_CPU0_P1_RX_DP<1>")
		)
		(pad "EL2" smd circle
			(at -7.850124 -3.41884)
			(size 0.3048 0.3048)
			(layers "F.Cu" "F.Mask" "F.Paste")
			(net "P5E_CPU0_P1_RX_BUF_DN<1>")
		)
		(pad "EL34" smd circle
			(at -7.850124 3.420364)
			(size 0.3048 0.3048)
			(layers "F.Cu" "F.Mask" "F.Paste")
			(net "P5E_CPU0_P1_TX_C_DP<1>")
		)
		(pad "EM10" smd circle
			(at -7.997444 -1.431798)
			(size 0.381 0.381)
			(layers "F.Cu" "F.Mask" "F.Paste")
			(net "P5E_CPU0_P1_TX_BUF_DN<1>")
		)
		(pad "EM29" smd circle
			(at -7.997444 2.032254)
			(size 0.381 0.381)
			(layers "F.Cu" "F.Mask" "F.Paste")
			(net "P5E_CPU0_P1_RX_DN<1>")
		)
		(pad "EN1" smd oval
			(at -8.150098 -3.938524)
			(size 0.254 0.3302)
			(layers "F.Cu" "F.Mask" "F.Paste")
			(net "P5E_CPU0_P1_RX_BUF_DP<1>")
		)
		(pad "EN35" smd oval
			(at -8.150098 3.940048)
			(size 0.254 0.3302)
			(layers "F.Cu" "F.Mask" "F.Paste")
			(net "P5E_CPU0_P1_TX_C_DN<1>")
		)
		(pad "EP4" smd circle
			(at -8.397494 -2.817368)
			(size 0.381 0.381)
			(layers "F.Cu" "F.Mask" "F.Paste")
			(net "GND")
		)
		(pad "EP13" smd circle
			(at -8.397494 -0.79629)
			(size 0.3048 0.3048)
			(layers "F.Cu" "F.Mask" "F.Paste")
			(net "GND")
		)
		(pad "EP17" smd circle
			(at -8.397494 -0.296164)
			(size 0.3048 0.3048)
			(layers "F.Cu" "F.Mask" "F.Paste")
			(net "P0V9_CPU0_RT1_2A")
		)
		(pad "EP20" smd circle
			(at -8.397494 0.203708)
			(size 0.3048 0.3048)
			(layers "F.Cu" "F.Mask" "F.Paste")
			(net "P0V9_CPU0_RT1_2A")
		)
		(pad "EP22" smd circle
			(at -8.397494 0.703834)
			(size 0.3048 0.3048)
			(layers "F.Cu" "F.Mask" "F.Paste")
			(net "GND")
		)
		(pad "EP32" smd circle
			(at -8.397494 2.724912)
			(size 0.381 0.381)
			(layers "F.Cu" "F.Mask" "F.Paste")
			(net "GND")
		)
		(pad "ER2" smd circle
			(at -8.450072 -3.41884)
			(size 0.3048 0.3048)
			(layers "F.Cu" "F.Mask" "F.Paste")
			(net "GND")
		)
		(pad "ER34" smd circle
			(at -8.450072 3.420364)
			(size 0.3048 0.3048)
			(layers "F.Cu" "F.Mask" "F.Paste")
			(net "GND")
		)
		(pad "ET1" smd oval
			(at -8.750046 -3.938524)
			(size 0.254 0.3302)
			(layers "F.Cu" "F.Mask" "F.Paste")
			(net "GND")
		)
		(pad "ET35" smd oval
			(at -8.750046 3.940048)
			(size 0.254 0.3302)
			(layers "F.Cu" "F.Mask" "F.Paste")
			(net "GND")
		)
		(pad "EU7" smd circle
			(at -8.79729 -2.12471)
			(size 0.381 0.381)
			(layers "F.Cu" "F.Mask" "F.Paste")
			(net "P5E_CPU0_P1_TX_BUF_DP<0>")
		)
		(pad "EU26" smd circle
			(at -8.79729 1.339342)
			(size 0.381 0.381)
			(layers "F.Cu" "F.Mask" "F.Paste")
			(net "P5E_CPU0_P1_RX_DP<0>")
		)
		(pad "EV2" smd circle
			(at -9.05002 -3.41884)
			(size 0.3048 0.3048)
			(layers "F.Cu" "F.Mask" "F.Paste")
			(net "P5E_CPU0_P1_RX_BUF_DN<0>")
		)
		(pad "EV34" smd circle
			(at -9.05002 3.420364)
			(size 0.3048 0.3048)
			(layers "F.Cu" "F.Mask" "F.Paste")
			(net "P5E_CPU0_P1_TX_C_DN<0>")
		)
		(pad "EW10" smd circle
			(at -9.19734 -1.431798)
			(size 0.381 0.381)
			(layers "F.Cu" "F.Mask" "F.Paste")
			(net "P5E_CPU0_P1_TX_BUF_DN<0>")
		)
		(pad "EW29" smd circle
			(at -9.19734 2.032254)
			(size 0.381 0.381)
			(layers "F.Cu" "F.Mask" "F.Paste")
			(net "P5E_CPU0_P1_RX_DN<0>")
		)
		(pad "EY1" smd oval
			(at -9.349994 -3.938524)
			(size 0.254 0.3302)
			(layers "F.Cu" "F.Mask" "F.Paste")
			(net "P5E_CPU0_P1_RX_BUF_DP<0>")
		)
		(pad "EY35" smd oval
			(at -9.349994 3.940048)
			(size 0.254 0.3302)
			(layers "F.Cu" "F.Mask" "F.Paste")
			(net "P5E_CPU0_P1_TX_C_DP<0>")
		)
		(pad "F2" smd circle
			(at 10.150094 -3.41884)
			(size 0.3048 0.3048)
			(layers "F.Cu" "F.Mask" "F.Paste")
			(net "RST_RT_CPU0_P1_PERST_N")
		)
		(pad "F34" smd circle
			(at 10.150094 3.420364)
			(size 0.3048 0.3048)
			(layers "F.Cu" "F.Mask" "F.Paste")
			(net "RT_CPU0_P1_ADDR1")
		)
		(pad "FA15" smd circle
			(at -9.59739 -0.738886)
			(size 0.381 0.381)
			(layers "F.Cu" "F.Mask" "F.Paste")
			(net "GND")
		)
		(pad "FA32" smd circle
			(at -9.59739 2.724912)
			(size 0.381 0.381)
			(layers "F.Cu" "F.Mask" "F.Paste")
			(net "GND")
		)
		(pad "FB2" smd circle
			(at -9.649968 -3.41884)
			(size 0.3048 0.3048)
			(layers "F.Cu" "F.Mask" "F.Paste")
			(net "GND")
		)
		(pad "FB34" smd circle
			(at -9.649968 3.420364)
			(size 0.3048 0.3048)
			(layers "F.Cu" "F.Mask" "F.Paste")
			(net "GND")
		)
		(pad "FC3" smd circle
			(at -9.846818 -2.888488)
			(size 0.3048 0.3048)
			(layers "F.Cu" "F.Mask" "F.Paste")
			(net "GND")
		)
		(pad "FC6" smd circle
			(at -9.846818 -2.288286)
			(size 0.3048 0.3048)
			(layers "F.Cu" "F.Mask" "F.Paste")
			(net "GND")
		)
		(pad "FC9" smd circle
			(at -9.846818 -1.688338)
			(size 0.3048 0.3048)
			(layers "F.Cu" "F.Mask" "F.Paste")
			(net "GND")
		)
		(pad "FC19" smd circle
			(at -9.846818 0.111506)
			(size 0.3048 0.3048)
			(layers "F.Cu" "F.Mask" "F.Paste")
			(net "GND")
		)
		(pad "FC23" smd circle
			(at -9.846818 0.711708)
			(size 0.3048 0.3048)
			(layers "F.Cu" "F.Mask" "F.Paste")
			(net "GND")
		)
		(pad "FC25" smd circle
			(at -9.846818 1.311656)
			(size 0.3048 0.3048)
			(layers "F.Cu" "F.Mask" "F.Paste")
			(net "GND")
		)
		(pad "FC28" smd circle
			(at -9.846818 1.911604)
			(size 0.3048 0.3048)
			(layers "F.Cu" "F.Mask" "F.Paste")
			(net "GND")
		)
		(pad "FD1" smd oval
			(at -9.949942 -3.938524)
			(size 0.254 0.3302)
			(layers "F.Cu" "F.Mask" "F.Paste")
			(net "GND")
		)
		(pad "FD35" smd oval
			(at -9.949942 3.940048)
			(size 0.254 0.3302)
			(layers "F.Cu" "F.Mask" "F.Paste")
			(net "GND")
		)
		(pad "FE2" smd circle
			(at -10.249916 -3.41884)
			(size 0.3048 0.3048)
			(layers "F.Cu" "F.Mask" "F.Paste")
			(net "NCF_CPU0_P1_GND")
		)
		(pad "FE34" smd circle
			(at -10.249916 3.420364)
			(size 0.3048 0.3048)
			(layers "F.Cu" "F.Mask" "F.Paste")
			(net "NCF_CPU0_P1_GND")
		)
		(pad "FF5" smd circle
			(at -10.366248 -2.588514)
			(size 0.3048 0.3048)
			(layers "F.Cu" "F.Mask" "F.Paste")
			(net "SMB_RT_CPU0_P1_ROM_MUX_1D_R_SCL")
		)
		(pad "FF8" smd circle
			(at -10.366248 -1.988312)
			(size 0.3048 0.3048)
			(layers "F.Cu" "F.Mask" "F.Paste")
			(net "JTAG_TEST_MODE_RT_CPU0_P1")
		)
		(pad "FF11" smd circle
			(at -10.366248 -1.388364)
			(size 0.3048 0.3048)
			(layers "F.Cu" "F.Mask" "F.Paste")
			(net "RST_RT_CPU0_P1_RESET_N")
		)
		(pad "FF14" smd circle
			(at -10.366248 -0.788416)
			(size 0.3048 0.3048)
			(layers "F.Cu" "F.Mask" "F.Paste")
			(net "GND")
		)
		(pad "FF18" smd circle
			(at -10.366248 -0.188468)
			(size 0.3048 0.3048)
			(layers "F.Cu" "F.Mask" "F.Paste")
			(net "CLK_100M_RETIMER_CPU0_P1_DN")
		)
		(pad "FF21" smd circle
			(at -10.366248 0.41148)
			(size 0.3048 0.3048)
			(layers "F.Cu" "F.Mask" "F.Paste")
			(net "GND")
		)
		(pad "FF24" smd circle
			(at -10.366248 1.011682)
			(size 0.3048 0.3048)
			(layers "F.Cu" "F.Mask" "F.Paste")
			(net "TEST0_RT_CPU0_P1")
		)
		(pad "FF27" smd circle
			(at -10.366248 1.61163)
			(size 0.3048 0.3048)
			(layers "F.Cu" "F.Mask" "F.Paste")
			(net "TEST1_RT_CPU0_P1")
		)
		(pad "FF30" smd circle
			(at -10.366248 2.211578)
			(size 0.3048 0.3048)
			(layers "F.Cu" "F.Mask" "F.Paste")
			(net "TEST2_RT_CPU0_P1")
		)
		(pad "FF33" smd circle
			(at -10.366248 2.811526)
			(size 0.3048 0.3048)
			(layers "F.Cu" "F.Mask" "F.Paste")
			(net "RT_CPU0_P1_SCAN_MODE")
		)
		(pad "FG1" smd oval
			(at -10.54989 -3.938524)
			(size 0.254 0.3302)
			(layers "F.Cu" "F.Mask" "F.Paste")
			(net "NCF_CPU0_P1_GND")
		)
		(pad "FG35" smd oval
			(at -10.54989 3.940048)
			(size 0.254 0.3302)
			(layers "F.Cu" "F.Mask" "F.Paste")
			(net "NCF_CPU0_P1_GND")
		)
		(pad "FH2" smd circle
			(at -10.850118 -3.41884)
			(size 0.3048 0.3048)
			(layers "F.Cu" "F.Mask" "F.Paste")
			(net "NCF_CPU0_P1_GND")
		)
		(pad "FH34" smd circle
			(at -10.850118 3.420364)
			(size 0.3048 0.3048)
			(layers "F.Cu" "F.Mask" "F.Paste")
			(net "NCF_CPU0_P1_GND")
		)
		(pad "FJ3" smd oval
			(at -10.885932 -2.888488 90)
			(size 0.254 0.3302)
			(layers "F.Cu" "F.Mask" "F.Paste")
			(net "SMB_RT_CPU0_P1_ROM_MUX_1D_R_SDA")
		)
		(pad "FJ6" smd oval
			(at -10.885932 -2.288286 90)
			(size 0.254 0.3302)
			(layers "F.Cu" "F.Mask" "F.Paste")
			(net "Net_2204")
		)
		(pad "FJ9" smd oval
			(at -10.885932 -1.688338 90)
			(size 0.254 0.3302)
			(layers "F.Cu" "F.Mask" "F.Paste")
			(net "MODE_RT_CPU0_P1")
		)
		(pad "FJ12" smd oval
			(at -10.885932 -1.08839 90)
			(size 0.254 0.3302)
			(layers "F.Cu" "F.Mask" "F.Paste")
			(net "GND")
		)
		(pad "FJ16" smd oval
			(at -10.885932 -0.488442 90)
			(size 0.254 0.3302)
			(layers "F.Cu" "F.Mask" "F.Paste")
			(net "CLK_100M_RETIMER_CPU0_P1_DP")
		)
		(pad "FJ19" smd oval
			(at -10.885932 0.111506 90)
			(size 0.254 0.3302)
			(layers "F.Cu" "F.Mask" "F.Paste")
			(net "GND")
		)
		(pad "FJ23" smd oval
			(at -10.885932 0.711708 90)
			(size 0.254 0.3302)
			(layers "F.Cu" "F.Mask" "F.Paste")
			(net "Net_2205")
		)
		(pad "FJ25" smd oval
			(at -10.885932 1.311656 90)
			(size 0.254 0.3302)
			(layers "F.Cu" "F.Mask" "F.Paste")
			(net "GPIO2_RT_CPU0_P1")
		)
		(pad "FJ28" smd oval
			(at -10.885932 1.911604 90)
			(size 0.254 0.3302)
			(layers "F.Cu" "F.Mask" "F.Paste")
			(net "GPIO3_RT_CPU0_P1")
		)
		(pad "FJ31" smd oval
			(at -10.885932 2.511552 90)
			(size 0.254 0.3302)
			(layers "F.Cu" "F.Mask" "F.Paste")
			(net "Net_51")
		)
		(pad "G1" smd oval
			(at 9.85012 -3.938524)
			(size 0.254 0.3302)
			(layers "F.Cu" "F.Mask" "F.Paste")
			(net "RT_CPU0_P1_VQPS")
		)
		(pad "G35" smd oval
			(at 9.85012 3.940048)
			(size 0.254 0.3302)
			(layers "F.Cu" "F.Mask" "F.Paste")
			(net "CLKREQ_RT_CPU0_P1_N")
		)
		(pad "H12" smd circle
			(at 9.846818 -1.08839)
			(size 0.3048 0.3048)
			(layers "F.Cu" "F.Mask" "F.Paste")
			(net "GND")
		)
		(pad "H16" smd circle
			(at 9.846818 -0.488442)
			(size 0.3048 0.3048)
			(layers "F.Cu" "F.Mask" "F.Paste")
			(net "GND")
		)
		(pad "H19" smd circle
			(at 9.846818 0.111506)
			(size 0.3048 0.3048)
			(layers "F.Cu" "F.Mask" "F.Paste")
			(net "GND")
		)
		(pad "H31" smd circle
			(at 9.846818 2.511552)
			(size 0.3048 0.3048)
			(layers "F.Cu" "F.Mask" "F.Paste")
			(net "GND")
		)
		(pad "J4" smd circle
			(at 9.602724 -2.817368)
			(size 0.381 0.381)
			(layers "F.Cu" "F.Mask" "F.Paste")
			(net "GND")
		)
		(pad "J22" smd circle
			(at 9.602724 0.703834)
			(size 0.3048 0.3048)
			(layers "F.Cu" "F.Mask" "F.Paste")
			(net "GND")
		)
		(pad "K2" smd circle
			(at 9.549892 -3.41884)
			(size 0.3048 0.3048)
			(layers "F.Cu" "F.Mask" "F.Paste")
			(net "GND")
		)
		(pad "K34" smd circle
			(at 9.549892 3.420364)
			(size 0.3048 0.3048)
			(layers "F.Cu" "F.Mask" "F.Paste")
			(net "GND")
		)
		(pad "L1" smd oval
			(at 9.249918 -3.938524)
			(size 0.254 0.3302)
			(layers "F.Cu" "F.Mask" "F.Paste")
			(net "GND")
		)
		(pad "L35" smd oval
			(at 9.249918 3.940048)
			(size 0.254 0.3302)
			(layers "F.Cu" "F.Mask" "F.Paste")
			(net "GND")
		)
		(pad "M7" smd circle
			(at 9.202674 -2.12471)
			(size 0.381 0.381)
			(layers "F.Cu" "F.Mask" "F.Paste")
			(net "P5E_CPU0_P1_TX_BUF_DP<15>")
		)
		(pad "M26" smd circle
			(at 9.202674 1.339342)
			(size 0.381 0.381)
			(layers "F.Cu" "F.Mask" "F.Paste")
			(net "P5E_CPU0_P1_RX_DP<15>")
		)
		(pad "N2" smd circle
			(at 8.949944 -3.41884)
			(size 0.3048 0.3048)
			(layers "F.Cu" "F.Mask" "F.Paste")
			(net "P5E_CPU0_P1_RX_BUF_DN<15>")
		)
		(pad "N34" smd circle
			(at 8.949944 3.420364)
			(size 0.3048 0.3048)
			(layers "F.Cu" "F.Mask" "F.Paste")
			(net "P5E_CPU0_P1_TX_C_DN<15>")
		)
	)
)
